FILE_TYPE = MULTI_PHYS_TABLE;

PART 'SCONN288_ADR50017P087CC'

{========================================================================================}
:VALUE                      | PART_TYPE | MATERIAL | PART_NUMBER    = STANDARD | LIFECYCLE     | PART_NUMBER   | JEDEC_TYPE       | DESCRIPTION                                | MANUFTR | MANUF_PN          | RD_CMPLS_LVL | CMPLS_LVL | CLASS | DIP_SMD | FROM_PJ    | DATA                      | FP_ECN                | EE_CHECK_LIST | CREATOR | CREATEDAY  | PSL | STATUS | ESD_CDM | ESD_HBM | ESD_MM | MSD | PIN_LENGTH_LONG_PIN | PIN_LENGTH_SHORT_PIN ;
{========================================================================================}
 'SCONN288_ADR50017-P087CC' | 'SMLF'    | 'IO'     | 'DFHST8FS460'(!) = ''       | ''               | 'DFHST8FS460' |'DDR288S_1-1VXB'| 'CONN SMD HS DDR5 288P 2R FS(P0.85,H21.3)' | 'LTS'   | 'ADR50017-P087CC' | 'EP(V1)'     | ''        | 'IO'  | ''      | 'F0C-IVES' | 'LTS_ADR50017-P087CC.pdf' | 'ADR50017-P087CC.msg' | ''            | ''      | '20210723' | ''  | ''     | ''      | ''      | ''     | ''  | '81 MILS'           | '81 MILS'           
 'SCONN288_ADR50017-P087CC' | 'SMLF'    | 'EMPTY'  | 'DFHST8FS460'(!) = ''       | ''               | 'DFHST8FS460' |'DDR288S_1-1VXB'| 'CONN SMD HS DDR5 288P 2R FS(P0.85,H21.3)' | 'LTS'   | 'ADR50017-P087CC' | 'EP(V1)'     | ''        | 'IO'  | ''      | 'F0C-IVES' | 'LTS_ADR50017-P087CC.pdf' | 'ADR50017-P087CC.msg' | ''            | ''      | '20210723' | ''  | ''     | ''      | ''      | ''     | ''  | '81 MILS'           | '81 MILS'           

END_PART

END.

